(kicad_pcb
	(version 20260206)
	(generator "pcbnew")
	(generator_version "10.0")
	(general
		(thickness 1.21888)
		(legacy_teardrops no)
	)
	(paper "A4")
	(title_block
		(title "timecard-v8 — TimeCard-DC-V8_EXP.PcbDoc")
		(comment 1 "Time Appliance Project (Time Card) / footprints 78-89 of 288")
	)
	(layers
		(0 "F.Cu" signal "TOP")
		(4 "In1.Cu" signal "SGND")
		(6 "In2.Cu" signal "IN1")
		(8 "In3.Cu" signal "IN2")
		(10 "In4.Cu" signal "SGND1")
		(2 "B.Cu" signal "BOTTOM")
		(9 "F.Adhes" user "F.Adhesive")
		(11 "B.Adhes" user "B.Adhesive")
		(13 "F.Paste" user "Top Paste")
		(15 "B.Paste" user "Bottom Paste")
		(5 "F.SilkS" user "Top Overlay")
		(7 "B.SilkS" user "Bottom Overlay")
		(1 "F.Mask" user "Top Solder")
		(3 "B.Mask" user "Bottom Solder")
		(17 "Dwgs.User" user "User.Drawings")
		(19 "Cmts.User" user "User.Comments")
		(21 "Eco1.User" user "User.Eco1")
		(23 "Eco2.User" user "User.Eco2")
		(25 "Edge.Cuts" user)
		(27 "Margin" user)
		(31 "F.CrtYd" user "Top Courtyard")
		(29 "B.CrtYd" user "Bottom Courtyard")
		(35 "F.Fab" user "Top Component Center")
		(33 "B.Fab" user "Bottom Component Center")
	)
	(footprint "Vault:RESC1005X40X25LL05T05"
		(layer "F.Cu")
		(at 191.3261 83.4162 -90)
		(property "Reference" "R58"
			(at -2.6714 -0.073069 270)
			(unlocked yes)
			(layer "F.SilkS")
			(effects
				(font
					(size 0.762 0.762)
					(thickness 0.2286)
				)
			)
		)
		(property "Value" "4.7K_0402"
			(at -3.024391 2.374045 180)
			(unlocked yes)
			(layer "F.SilkS")
			(hide yes)
			(effects
				(font
					(size 0.762 0.762)
					(thickness 0.2286)
				)
			)
		)
		(sheetname "GPS_IMU_SENSORS")
		(sheetfile "GPS_IMU_SENSORS.kicad_sch")
		(duplicate_pad_numbers_are_jumpers no)
		(pad "1" smd rect
			(at -0.4 0)
			(size 0.45 0.45)
			(layers "F.Cu" "F.Mask" "F.Paste")
			(net "+3.3V")
		)
		(pad "2" smd rect
			(at 0.4 0)
			(size 0.45 0.45)
			(layers "F.Cu" "F.Mask" "F.Paste")
			(net "NetR58_2")
		)
	)
	(footprint "Vault:CAPC1005X56X25NL10T15"
		(layer "F.Cu")
		(at 189.6261 91.0162 180)
		(property "Reference" "C33"
			(at -2.5286 -0.426931 0)
			(unlocked yes)
			(layer "F.SilkS")
			(effects
				(font
					(size 0.762 0.762)
					(thickness 0.2286)
				)
			)
		)
		(property "Value" "0.1uF_0402"
			(at 2.06903 2.567201 180)
			(unlocked yes)
			(layer "F.SilkS")
			(hide yes)
			(effects
				(font
					(size 0.762 0.762)
					(thickness 0.2286)
				)
			)
		)
		(sheetname "GPS_IMU_SENSORS")
		(sheetfile "GPS_IMU_SENSORS.kicad_sch")
		(duplicate_pad_numbers_are_jumpers no)
		(pad "1" smd rect
			(at -0.44 0 270)
			(size 0.64 0.68)
			(layers "F.Cu" "F.Mask" "F.Paste")
			(net "BNO_XOUT32_C")
		)
		(pad "2" smd rect
			(at 0.44 0 270)
			(size 0.64 0.68)
			(layers "F.Cu" "F.Mask" "F.Paste")
			(net "BNO_XOUT32")
		)
	)
	(footprint "Vault:RESC0402(1005)_N"
		(layer "F.Cu")
		(at 217.5261 130.1162 -90)
		(property "Reference" "R69"
			(at 0.8286 -1.073069 270)
			(unlocked yes)
			(layer "F.SilkS")
			(effects
				(font
					(size 0.762 0.762)
					(thickness 0.2286)
				)
			)
		)
		(property "Value" "1.21_1%_0402"
			(at -2.783071 8.468155 180)
			(unlocked yes)
			(layer "F.SilkS")
			(hide yes)
			(effects
				(font
					(size 0.762 0.762)
					(thickness 0.2286)
				)
			)
		)
		(sheetname "POWER")
		(sheetfile "POWER.kicad_sch")
		(duplicate_pad_numbers_are_jumpers no)
		(pad "1" smd rect
			(at -0.5 0)
			(size 0.65 0.55)
			(layers "F.Cu" "F.Mask" "F.Paste")
			(net "NetR69_1")
		)
		(pad "2" smd rect
			(at 0.5 0)
			(size 0.65 0.55)
			(layers "F.Cu" "F.Mask" "F.Paste")
			(net "NetC68_1")
		)
	)
	(footprint "Vault:RESC1005X40X25ML05T10"
		(layer "F.Cu")
		(at 204.0261 109.3162 -90)
		(property "Reference" "R59"
			(at -0.1286 1.473069 90)
			(unlocked yes)
			(layer "F.SilkS")
			(effects
				(font
					(size 0.762 0.762)
					(thickness 0.2286)
				)
			)
		)
		(property "Value" "2.21_1%_0402"
			(at -2.884671 8.544305 180)
			(unlocked yes)
			(layer "F.SilkS")
			(hide yes)
			(effects
				(font
					(size 0.762 0.762)
					(thickness 0.2286)
				)
			)
		)
		(sheetname "POWER")
		(sheetfile "POWER.kicad_sch")
		(duplicate_pad_numbers_are_jumpers no)
		(pad "1" smd rect
			(at -0.475 0)
			(size 0.65 0.7)
			(layers "F.Cu" "F.Mask" "F.Paste")
			(net "+12V")
		)
		(pad "2" smd rect
			(at 0.475 0)
			(size 0.65 0.7)
			(layers "F.Cu" "F.Mask" "F.Paste")
			(net "NetC6_1")
		)
	)
	(footprint "SamacSys:155124M173200"
		(layer "F.Cu")
		(at 58.4511 101.4162 90)
		(property "Reference" "D15"
			(at -0.4714 1.701931 90)
			(unlocked yes)
			(layer "F.SilkS")
			(effects
				(font
					(size 0.762 0.762)
					(thickness 0.2286)
				)
			)
		)
		(property "Value" "155124M173200"
			(at 7.1471 2.605271 90)
			(unlocked yes)
			(layer "F.SilkS")
			(hide yes)
			(effects
				(font
					(size 0.762 0.762)
					(thickness 0.2286)
				)
			)
		)
		(sheetname "USER_IO_STATUS")
		(sheetfile "USER_IO_STATUS.kicad_sch")
		(duplicate_pad_numbers_are_jumpers no)
		(fp_line
			(start -0.8 0.5)
			(end 0.8 0.5)
			(stroke
				(width 0.1)
				(type solid)
			)
			(layer "F.SilkS")
		)
		(fp_arc
			(start -2 -0.1)
			(mid -1.95 -0.05)
			(end -2 0)
			(stroke
				(width 0.1)
				(type solid)
			)
			(layer "F.SilkS")
		)
		(fp_arc
			(start -2 0)
			(mid -2.05 -0.05)
			(end -2 -0.1)
			(stroke
				(width 0.1)
				(type solid)
			)
			(layer "F.SilkS")
		)
		(pad "1" smd rect
			(at -1.4 0 180)
			(size 0.9 0.6)
			(layers "F.Cu" "F.Mask" "F.Paste")
			(net "+3.3V")
		)
		(pad "2" smd rect
			(at -0.45 -0.325 90)
			(size 0.6 0.55)
			(layers "F.Cu" "F.Mask" "F.Paste")
			(net "NetD15_2")
		)
		(pad "3" smd rect
			(at 0.45 -0.325 90)
			(size 0.6 0.55)
			(layers "F.Cu" "F.Mask" "F.Paste")
			(net "NetD15_3")
		)
		(pad "4" smd rect
			(at 1.4 0 180)
			(size 0.9 0.6)
			(layers "F.Cu" "F.Mask" "F.Paste")
			(net "NetD15_4")
		)
	)
	(footprint "Vault:RESC1005X40X25NL05T05"
		(layer "F.Cu")
		(at 208.8261 80.6162)
		(property "Reference" "R93"
			(at -1.9714 -0.173069 0)
			(unlocked yes)
			(layer "F.SilkS")
			(effects
				(font
					(size 0.762 0.762)
					(thickness 0.2286)
				)
			)
		)
		(property "Value" "27_1%_0402"
			(at -2.732271 7.37632 270)
			(unlocked yes)
			(layer "F.SilkS")
			(hide yes)
			(effects
				(font
					(size 0.762 0.762)
					(thickness 0.2286)
				)
			)
		)
		(sheetname "USBUart_DipSelects")
		(sheetfile "USBUart_DipSelects.kicad_sch")
		(duplicate_pad_numbers_are_jumpers no)
		(pad "1" smd rect
			(at -0.45 0 90)
			(size 0.55 0.55)
			(layers "F.Cu" "F.Mask" "F.Paste")
			(net "GPS2_RX_FPGA")
		)
		(pad "2" smd rect
			(at 0.45 0 90)
			(size 0.55 0.55)
			(layers "F.Cu" "F.Mask" "F.Paste")
			(net "NetR93_2")
		)
	)
	(footprint "Vault:FP-C3216-160-0_2-MFG"
		(layer "F.Cu")
		(at 231.8261 123.3162)
		(property "Reference" "C78"
			(at 4.0286 0.226931 0)
			(unlocked yes)
			(layer "F.SilkS")
			(effects
				(font
					(size 0.762 0.762)
					(thickness 0.2286)
				)
			)
		)
		(property "Value" "47uF_16V_1206"
			(at -4.014951 8.77266 270)
			(unlocked yes)
			(layer "F.SilkS")
			(hide yes)
			(effects
				(font
					(size 0.762 0.762)
					(thickness 0.2286)
				)
			)
		)
		(sheetname "POWER")
		(sheetfile "POWER.kicad_sch")
		(duplicate_pad_numbers_are_jumpers no)
		(fp_line
			(start -0.725 -0.9)
			(end 0.725 -0.9)
			(stroke
				(width 0.2)
				(type solid)
			)
			(layer "F.SilkS")
		)
		(fp_line
			(start -0.725 0.9)
			(end 0.725 0.9)
			(stroke
				(width 0.2)
				(type solid)
			)
			(layer "F.SilkS")
		)
		(fp_line
			(start -2.3 -1)
			(end 2.3 -1)
			(stroke
				(width 0.2)
				(type solid)
			)
			(layer "F.CrtYd")
		)
		(fp_line
			(start -2.3 1)
			(end -2.3 -1)
			(stroke
				(width 0.2)
				(type solid)
			)
			(layer "F.CrtYd")
		)
		(fp_line
			(start -2.3 1)
			(end 2.3 1)
			(stroke
				(width 0.2)
				(type solid)
			)
			(layer "F.CrtYd")
		)
		(fp_line
			(start 2.3 1)
			(end 2.3 -1)
			(stroke
				(width 0.2)
				(type solid)
			)
			(layer "F.CrtYd")
		)
		(fp_line
			(start -2.3 -1)
			(end 2.3 -1)
			(stroke
				(width 0.2)
				(type solid)
			)
			(layer "F.Fab")
		)
		(fp_line
			(start -2.3 1)
			(end -2.3 -1)
			(stroke
				(width 0.2)
				(type solid)
			)
			(layer "F.Fab")
		)
		(fp_line
			(start -2.3 1)
			(end 2.3 1)
			(stroke
				(width 0.2)
				(type solid)
			)
			(layer "F.Fab")
		)
		(fp_line
			(start -0.5 0)
			(end 0.5 0)
			(stroke
				(width 0.1)
				(type solid)
			)
			(layer "F.Fab")
		)
		(fp_line
			(start 0 0.5)
			(end 0 -0.5)
			(stroke
				(width 0.1)
				(type solid)
			)
			(layer "F.Fab")
		)
		(fp_line
			(start 2.3 1)
			(end 2.3 -1)
			(stroke
				(width 0.2)
				(type solid)
			)
			(layer "F.Fab")
		)
		(fp_text user "${REFERENCE}"
			(at -0.00001 0.09602 360)
			(unlocked yes)
			(layer "F.Fab")
			(effects
				(font
					(face "Arial")
					(size 0.63 0.63)
					(thickness 0.1)
				)
				(justify left bottom)
			)
		)
		(pad "1" smd rect
			(at -1.65 0)
			(size 1.1 1.35)
			(layers "F.Cu" "F.Mask" "F.Paste")
			(net "+3.3V")
			(solder_mask_margin 0)
			(solder_paste_margin 0)
		)
		(pad "2" smd rect
			(at 1.65 0)
			(size 1.1 1.35)
			(layers "F.Cu" "F.Mask" "F.Paste")
			(net "GND")
			(solder_mask_margin 0)
			(solder_paste_margin 0)
		)
	)
	(footprint "Vault:RESC1005X40X25NL05T05"
		(layer "F.Cu")
		(at 217.2261 77.9162)
		(property "Reference" "R85"
			(at 0.0286 -0.973079 0)
			(unlocked yes)
			(layer "F.SilkS")
			(effects
				(font
					(size 0.762 0.762)
					(thickness 0.2286)
				)
			)
		)
		(property "Value" "27_1%_0402"
			(at -2.732281 7.37632 270)
			(unlocked yes)
			(layer "F.SilkS")
			(hide yes)
			(effects
				(font
					(size 0.762 0.762)
					(thickness 0.2286)
				)
			)
		)
		(sheetname "USBUart_DipSelects")
		(sheetfile "USBUart_DipSelects.kicad_sch")
		(duplicate_pad_numbers_are_jumpers no)
		(pad "1" smd rect
			(at -0.45 0 90)
			(size 0.55 0.55)
			(layers "F.Cu" "F.Mask" "F.Paste")
			(net "FTDI_RX")
		)
		(pad "2" smd rect
			(at 0.45 0 90)
			(size 0.55 0.55)
			(layers "F.Cu" "F.Mask" "F.Paste")
			(net "NetR85_2")
		)
	)
	(footprint "Vault:RESC1005X40X25LL05T05"
		(layer "F.Cu")
		(at 192.3261 83.4162 -90)
		(property "Reference" "R57"
			(at -2.4714 -0.173069 270)
			(unlocked yes)
			(layer "F.SilkS")
			(effects
				(font
					(size 0.762 0.762)
					(thickness 0.2286)
				)
			)
		)
		(property "Value" "4.7K_0402"
			(at -3.024391 2.374045 180)
			(unlocked yes)
			(layer "F.SilkS")
			(hide yes)
			(effects
				(font
					(size 0.762 0.762)
					(thickness 0.2286)
				)
			)
		)
		(sheetname "GPS_IMU_SENSORS")
		(sheetfile "GPS_IMU_SENSORS.kicad_sch")
		(duplicate_pad_numbers_are_jumpers no)
		(pad "1" smd rect
			(at -0.4 0)
			(size 0.45 0.45)
			(layers "F.Cu" "F.Mask" "F.Paste")
			(net "+3.3V")
		)
		(pad "2" smd rect
			(at 0.4 0)
			(size 0.45 0.45)
			(layers "F.Cu" "F.Mask" "F.Paste")
			(net "NetR57_2")
		)
	)
	(footprint "Vault:FP-0402-L_1_0_1-W_0_5_0_1-IPC_C"
		(layer "F.Cu")
		(at 239.4261 64.75066 90)
		(property "Reference" "C92"
			(at 2.20586 0.373069 270)
			(unlocked yes)
			(layer "F.SilkS")
			(effects
				(font
					(size 0.762 0.762)
					(thickness 0.2286)
				)
			)
		)
		(property "Value" "0.1uF_25V_0402"
			(at -2.465551 9.839205 0)
			(unlocked yes)
			(layer "F.SilkS")
			(hide yes)
			(effects
				(font
					(size 0.762 0.762)
					(thickness 0.2286)
				)
			)
		)
		(sheetname "USBUart_DipSelects")
		(sheetfile "USBUart_DipSelects.kicad_sch")
		(duplicate_pad_numbers_are_jumpers no)
		(fp_line
			(start -0.65607 -0.7)
			(end 0.65606 -0.7)
			(stroke
				(width 0.2)
				(type solid)
			)
			(layer "F.SilkS")
		)
		(fp_line
			(start -0.65607 0.7)
			(end 0.65606 0.7)
			(stroke
				(width 0.2)
				(type solid)
			)
			(layer "F.SilkS")
		)
		(fp_line
			(start 0.75606 -0.4)
			(end 0.75606 0.4)
			(stroke
				(width 0.2)
				(type solid)
			)
			(layer "F.CrtYd")
		)
		(fp_line
			(start -0.75607 -0.4)
			(end 0.75606 -0.4)
			(stroke
				(width 0.2)
				(type solid)
			)
			(layer "F.CrtYd")
		)
		(fp_line
			(start -0.75607 -0.4)
			(end -0.75607 0.4)
			(stroke
				(width 0.2)
				(type solid)
			)
			(layer "F.CrtYd")
		)
		(fp_line
			(start -0.75607 0.4)
			(end 0.75606 0.4)
			(stroke
				(width 0.2)
				(type solid)
			)
			(layer "F.CrtYd")
		)
		(fp_line
			(start 0 -0.5)
			(end 0 0.5)
			(stroke
				(width 0.1)
				(type solid)
			)
			(layer "F.Fab")
		)
		(fp_line
			(start 0.75606 -0.4)
			(end 0.75606 0.4)
			(stroke
				(width 0.2)
				(type solid)
			)
			(layer "F.Fab")
		)
		(fp_line
			(start -0.75607 -0.4)
			(end 0.75606 -0.4)
			(stroke
				(width 0.2)
				(type solid)
			)
			(layer "F.Fab")
		)
		(fp_line
			(start -0.75607 -0.4)
			(end -0.75607 0.4)
			(stroke
				(width 0.2)
				(type solid)
			)
			(layer "F.Fab")
		)
		(fp_line
			(start -0.5 0)
			(end 0.5 0)
			(stroke
				(width 0.1)
				(type solid)
			)
			(layer "F.Fab")
		)
		(fp_line
			(start -0.75607 0.4)
			(end 0.75606 0.4)
			(stroke
				(width 0.2)
				(type solid)
			)
			(layer "F.Fab")
		)
		(fp_text user "${REFERENCE}"
			(at -0.00001 0.09601 90)
			(unlocked yes)
			(layer "F.Fab")
			(effects
				(font
					(face "Arial")
					(size 0.63 0.63)
					(thickness 0.1)
				)
				(justify left bottom)
			)
		)
		(pad "1" smd rect
			(at -0.36554 0 90)
			(size 0.58106 0.51213)
			(layers "F.Cu" "F.Mask" "F.Paste")
			(net "NetC92_1")
			(solder_mask_margin 0)
			(solder_paste_margin 0)
		)
		(pad "2" smd rect
			(at 0.36553 0 90)
			(size 0.58106 0.51213)
			(layers "F.Cu" "F.Mask" "F.Paste")
			(net "GND")
			(solder_mask_margin 0)
			(solder_paste_margin 0)
		)
	)
	(footprint "SamacSys:155124M173200"
		(layer "F.Cu")
		(at 58.4511 114.8162 90)
		(property "Reference" "D16"
			(at -0.5714 1.701931 90)
			(unlocked yes)
			(layer "F.SilkS")
			(effects
				(font
					(size 0.762 0.762)
					(thickness 0.2286)
				)
			)
		)
		(property "Value" "155124M173200"
			(at 7.1471 2.605271 90)
			(unlocked yes)
			(layer "F.SilkS")
			(hide yes)
			(effects
				(font
					(size 0.762 0.762)
					(thickness 0.2286)
				)
			)
		)
		(sheetname "USER_IO_STATUS")
		(sheetfile "USER_IO_STATUS.kicad_sch")
		(duplicate_pad_numbers_are_jumpers no)
		(fp_line
			(start -0.8 0.5)
			(end 0.8 0.5)
			(stroke
				(width 0.1)
				(type solid)
			)
			(layer "F.SilkS")
		)
		(fp_arc
			(start -2 -0.1)
			(mid -1.95 -0.05)
			(end -2 0)
			(stroke
				(width 0.1)
				(type solid)
			)
			(layer "F.SilkS")
		)
		(fp_arc
			(start -2 0)
			(mid -2.05 -0.05)
			(end -2 -0.1)
			(stroke
				(width 0.1)
				(type solid)
			)
			(layer "F.SilkS")
		)
		(pad "1" smd rect
			(at -1.4 0 180)
			(size 0.9 0.6)
			(layers "F.Cu" "F.Mask" "F.Paste")
			(net "+3.3V")
		)
		(pad "2" smd rect
			(at -0.45 -0.325 90)
			(size 0.6 0.55)
			(layers "F.Cu" "F.Mask" "F.Paste")
			(net "NetD16_2")
		)
		(pad "3" smd rect
			(at 0.45 -0.325 90)
			(size 0.6 0.55)
			(layers "F.Cu" "F.Mask" "F.Paste")
			(net "NetD16_3")
		)
		(pad "4" smd rect
			(at 1.4 0 180)
			(size 0.9 0.6)
			(layers "F.Cu" "F.Mask" "F.Paste")
			(net "NetD16_4")
		)
	)
	(footprint "SA53:SolderSocket"
		(layer "F.Cu")
		(at 139.9261 135.5162 90)
		(property "Reference" "SKT9"
			(at -2.626921 7.6286 0)
			(unlocked yes)
			(layer "F.SilkS")
			(effects
				(font
					(size 0.762 0.762)
					(thickness 0.2286)
				)
			)
		)
		(property "Value" "0332-0-43-80-18-27-10-0"
			(at -2.910071 16.1362 0)
			(unlocked yes)
			(layer "F.SilkS")
			(hide yes)
			(effects
				(font
					(size 0.762 0.762)
					(thickness 0.2286)
				)
			)
		)
		(sheetname "MAC")
		(sheetfile "MAC.kicad_sch")
		(duplicate_pad_numbers_are_jumpers no)
		(pad "1" thru_hole circle
			(at 0 0 90)
			(size 2.54 2.54)
			(drill 2.0066)
			(layers "*.Cu" "*.Mask")
			(remove_unused_layers no)
			(net "GND")
			(thermal_bridge_angle 90)
		)
	)
)
